# BASEBOARD_FAB2 (Tioga Pass) — schematic netlist excerpt (pin names and nets, part order shuffled) for the footprints in the layout excerpt that follows; sources: Cadence DE-HDL packaged netlist, KiCad conversion of Wiwynn_Tioga_Pass_MB.brd

U1W2  TCA9517DGKR-GP  pkg DISCRET-G8  page 248
  VCCA  = PVCCIO_CPU0
  SCLA  = SMB_CPU0_PE_HP_GTL_R_SCL
  SDAA  = SMB_CPU0_PE_HP_GTL_R_SDA
  GND  = GND
  EN  = TP_SMB_PEHPCPU0_EN
  SDAB  = SMB_PEHPCPU0_STBY_LVC3_R_SDA
  SCLB  = SMB_PEHPCPU0_STBY_LVC3_R_SCL
  VCCB  = P3V3_STBY

C5D5  CAP_A  22.0UF 4V 20% X6S  pkg 0603V  page 42 : A = PVCCIN_CPU0 ; B = GND

(kicad_pcb
	(version 20260206)
	(generator "pcbnew")
	(generator_version "10.0")
	(general
		(thickness 1.6)
		(legacy_teardrops no)
	)
	(paper "A4")
	(title_block
		(title "Wiwynn_Tioga_Pass_MB.brd")
		(comment 1 "Tioga Pass / footprints 1245-1246 of 4770")
	)
	(layers
		(0 "F.Cu" signal "TOP")
		(4 "In1.Cu" signal "L2GND")
		(6 "In2.Cu" signal "L3")
		(8 "In3.Cu" signal "L4GND")
		(10 "In4.Cu" signal "L5")
		(12 "In5.Cu" signal "L6GND")
		(14 "In6.Cu" signal "L7VCC")
		(16 "In7.Cu" signal "L8VCC")
		(18 "In8.Cu" signal "L9GND")
		(20 "In9.Cu" signal "L10")
		(22 "In10.Cu" signal "L11GND")
		(24 "In11.Cu" signal "L12")
		(26 "In12.Cu" signal "L13GND")
		(2 "B.Cu" signal "BOTTOM")
		(9 "F.Adhes" user "F.Adhesive")
		(11 "B.Adhes" user "B.Adhesive")
		(13 "F.Paste" user "Package Geometry/Pastemask Top")
		(15 "B.Paste" user "Package Geometry/Pastemask Bottom")
		(5 "F.SilkS" user "Ref Des/Silkscreen Top")
		(7 "B.SilkS" user "Ref Des/Silkscreen Bottom")
		(1 "F.Mask" user "Board Geometry/Soldermask Top")
		(3 "B.Mask" user "Board Geometry/Soldermask Bottom")
		(17 "Dwgs.User" user "User.Drawings")
		(19 "Cmts.User" user "User.Comments")
		(21 "Eco1.User" user "User.Eco1")
		(23 "Eco2.User" user "User.Eco2")
		(25 "Edge.Cuts" user "Board Geometry/Outline")
		(27 "Margin" user)
		(31 "F.CrtYd" user "Package Geometry/Place Bound Top")
		(29 "B.CrtYd" user "Package Geometry/Place Bound Bottom")
		(35 "F.Fab" user "Ref Des/Assembly Top")
		(33 "B.Fab" user "Ref Des/Assembly Bottom")
	)
	(footprint ""
		(layer "F.Cu")
		(at 420.624 -109.07014)
		(property "Reference" "U1W2"
			(at 0 0 0)
			(layer "F.SilkS")
			(hide yes)
			(effects
				(font
					(size 1.27 1.27)
				)
			)
		)
		(property "Value" "*"
			(at -0.1143 -9.3091 0)
			(unlocked yes)
			(layer "F.Fab")
			(hide yes)
			(effects
				(font
					(size 1.27 1.016)
					(thickness 0.1524)
				)
			)
		)
		(property "Device Type" "TCA9517DGKR-GP_DISCRET-G8-TCA9A"
			(at -0.1143 -10.9093 0)
			(unlocked yes)
			(layer "F.Fab")
			(hide yes)
			(effects
				(font
					(size 1.27 1.016)
					(thickness 0.1524)
				)
			)
		)
		(duplicate_pad_numbers_are_jumpers no)
		(fp_line
			(start -1.9558 -1.016)
			(end -1.9558 1.016)
			(stroke
				(width 0.1524)
				(type default)
			)
			(layer "F.SilkS")
		)
		(fp_line
			(start -1.9558 -0.5461)
			(end -1.4478 -0.0381)
			(stroke
				(width 0.1524)
				(type default)
			)
			(layer "F.SilkS")
		)
		(fp_line
			(start -1.9558 1.016)
			(end 1.0795 1.016)
			(stroke
				(width 0.1524)
				(type default)
			)
			(layer "F.SilkS")
		)
		(fp_line
			(start -1.778 1.0922)
			(end -1.778 3.048)
			(stroke
				(width 0.508)
				(type default)
			)
			(layer "F.SilkS")
		)
		(fp_line
			(start -1.4478 -0.0381)
			(end -1.9558 0.4699)
			(stroke
				(width 0.1524)
				(type default)
			)
			(layer "F.SilkS")
		)
		(fp_line
			(start 1.0795 -1.016)
			(end -1.9558 -1.016)
			(stroke
				(width 0.1524)
				(type default)
			)
			(layer "F.SilkS")
		)
		(fp_line
			(start 1.0795 1.016)
			(end 1.0795 -1.016)
			(stroke
				(width 0.1524)
				(type default)
			)
			(layer "F.SilkS")
		)
		(fp_poly
			(pts
				(xy -1.1557 -1.016) (xy -1.1557 1.016) (xy 1.1557 1.016) (xy 1.1557 -1.016)
			)
			(stroke
				(width 0)
				(type default)
			)
			(fill yes)
			(layer "F.SilkS")
		)
		(fp_rect
			(start -1.4986 2.4511)
			(end 1.4986 -2.4511)
			(stroke
				(width 0)
				(type default)
			)
			(fill no)
			(layer "F.CrtYd")
		)
		(fp_poly
			(pts
				(xy -2.032 3.302) (xy -2.032 -3.302) (xy 2.032 -3.302) (xy 2.032 -2.1209) (xy 1.4986 -2.1209) (xy 1.4986 -2.4511)
				(xy -1.4986 -2.4511) (xy -1.4986 2.4511) (xy 1.4986 2.4511) (xy 1.4986 -2.1082) (xy 2.032 -2.1082)
				(xy 2.032 3.302)
			)
			(stroke
				(width 0)
				(type default)
			)
			(fill no)
			(layer "F.CrtYd")
		)
		(fp_rect
			(start -2.032 3.302)
			(end 2.032 -3.302)
			(stroke
				(width 0)
				(type default)
			)
			(fill no)
			(layer "F.Fab")
		)
		(pad "1" smd rect
			(at -0.97536 2.05486)
			(size 0.3556 1.524)
			(layers "F.Cu" "F.Mask" "F.Paste")
			(net "PVCCIO_CPU0")
		)
		(pad "2" smd rect
			(at -0.32512 2.05486)
			(size 0.3556 1.524)
			(layers "F.Cu" "F.Mask" "F.Paste")
			(net "SMB_CPU0_PE_HP_GTL_R_SCL")
		)
		(pad "3" smd rect
			(at 0.32512 2.05486)
			(size 0.3556 1.524)
			(layers "F.Cu" "F.Mask" "F.Paste")
			(net "SMB_CPU0_PE_HP_GTL_R_SDA")
		)
		(pad "4" smd rect
			(at 0.97536 2.05486)
			(size 0.3556 1.524)
			(layers "F.Cu" "F.Mask" "F.Paste")
			(net "GND")
		)
		(pad "5" smd rect
			(at 0.97536 -2.05486)
			(size 0.3556 1.524)
			(layers "F.Cu" "F.Mask" "F.Paste")
			(net "TP_SMB_PEHPCPU0_EN")
		)
		(pad "6" smd rect
			(at 0.32512 -2.05486)
			(size 0.3556 1.524)
			(layers "F.Cu" "F.Mask" "F.Paste")
			(net "SMB_PEHPCPU0_STBY_LVC3_R_SDA")
		)
		(pad "7" smd rect
			(at -0.32512 -2.05486)
			(size 0.3556 1.524)
			(layers "F.Cu" "F.Mask" "F.Paste")
			(net "SMB_PEHPCPU0_STBY_LVC3_R_SCL")
		)
		(pad "8" smd rect
			(at -0.97536 -2.05486)
			(size 0.3556 1.524)
			(layers "F.Cu" "F.Mask" "F.Paste")
			(net "P3V3_STBY")
		)
	)
	(footprint ""
		(layer "F.Cu")
		(at 274.43303 -84.796122)
		(property "Reference" "C5D5"
			(at 0 0 0)
			(layer "F.SilkS")
			(hide yes)
			(effects
				(font
					(size 1.27 1.27)
				)
			)
		)
		(property "Value" ""
			(at 0 0 0)
			(layer "F.Fab")
			(effects
				(font
					(size 1.27 1.27)
				)
			)
		)
		(duplicate_pad_numbers_are_jumpers no)
		(fp_poly
			(pts
				(xy -0.4953 -0.2032) (xy 0.4953 -0.2032) (xy 0.4953 1.6002) (xy -0.4953 1.6002)
			)
			(stroke
				(width 0)
				(type default)
			)
			(fill no)
			(layer "F.CrtYd")
		)
		(fp_line
			(start -0.4953 -0.2032)
			(end 0.4953 -0.2032)
			(stroke
				(width 0.1)
				(type default)
			)
			(layer "F.Fab")
		)
		(fp_line
			(start -0.4953 1.6002)
			(end -0.4953 -0.2032)
			(stroke
				(width 0.1)
				(type default)
			)
			(layer "F.Fab")
		)
		(fp_line
			(start 0.4953 -0.2032)
			(end 0.4953 1.6002)
			(stroke
				(width 0.1)
				(type default)
			)
			(layer "F.Fab")
		)
		(fp_line
			(start 0.4953 1.6002)
			(end -0.4953 1.6002)
			(stroke
				(width 0.1)
				(type default)
			)
			(layer "F.Fab")
		)
		(pad "1" smd rect
			(at 0 0)
			(size 0.762 0.889)
			(layers "F.Cu" "F.Mask" "F.Paste")
			(net "PVCCIN_CPU0")
		)
		(pad "2" smd rect
			(at 0 1.397)
			(size 0.762 0.889)
			(layers "F.Cu" "F.Mask" "F.Paste")
			(net "GND")
		)
		(zone
			(layer "F.Cu")
			(hatch none 0.5)
			(connect_pads
				(clearance 0)
			)
			(min_thickness 0.25)
			(keepout
				(tracks not_allowed)
				(vias allowed)
				(pads allowed)
				(copperpour not_allowed)
				(footprints allowed)
			)
			(placement
				(enabled no)
				(sheetname "")
			)
			(fill
				(thermal_gap 0.5)
				(thermal_bridge_width 0.5)
				(island_removal_mode 0)
			)
			(polygon
				(pts
					(xy 274.05203 -84.351622) (xy 274.81403 -84.351622) (xy 274.81403 -83.843622) (xy 274.05203 -83.843622)
				)
			)
		)
	)
)
